(kicad_pcb
	(version 20260206)
	(generator "pcbnew")
	(generator_version "10.0")
	(general
		(thickness 1.6)
		(legacy_teardrops no)
	)
	(paper "A4")
	(title_block
		(title "v1-pdb — T6M_PDB_D_0927_0900.brd")
		(comment 1 "Open CloudServer (Microsoft) / footprint 314 of 321 (J10), pads 1-46 of 46")
	)
	(layers
		(0 "F.Cu" signal "TOP")
		(4 "In1.Cu" signal "GND")
		(6 "In2.Cu" signal "IN1")
		(8 "In3.Cu" signal "VCC")
		(10 "In4.Cu" signal "VCC1")
		(12 "In5.Cu" signal "IN2")
		(14 "In6.Cu" signal "GND1")
		(2 "B.Cu" signal "BOTTOM")
		(9 "F.Adhes" user "F.Adhesive")
		(11 "B.Adhes" user "B.Adhesive")
		(13 "F.Paste" user "Package Geometry/Pastemask Top")
		(15 "B.Paste" user "Package Geometry/Pastemask Bottom")
		(5 "F.SilkS" user "Ref Des/Silkscreen Top")
		(7 "B.SilkS" user "Ref Des/Silkscreen Bottom")
		(1 "F.Mask" user "Board Geometry/Soldermask Top")
		(3 "B.Mask" user "Board Geometry/Soldermask Bottom")
		(17 "Dwgs.User" user "User.Drawings")
		(19 "Cmts.User" user "User.Comments")
		(21 "Eco1.User" user "User.Eco1")
		(23 "Eco2.User" user "User.Eco2")
		(25 "Edge.Cuts" user "Board Geometry/Outline")
		(27 "Margin" user)
		(31 "F.CrtYd" user "Package Geometry/Place Bound Top")
		(29 "B.CrtYd" user "Package Geometry/Place Bound Bottom")
		(35 "F.Fab" user "Ref Des/Assembly Top")
		(33 "B.Fab" user "Ref Des/Assembly Bottom")
	)
	(footprint ""
		(layer "B.Cu")
		(at 44.040044 -141.61008 90)
		(property "Reference" "J10"
			(at 6.161024 -4.691126 0)
			(unlocked yes)
			(layer "B.SilkS")
			(effects
				(font
					(size 0.7874 0.5842)
					(thickness 0.1524)
				)
				(justify left mirror)
			)
		)
		(property "Value" ""
			(at 0 0 90)
			(layer "B.Fab")
			(effects
				(font
					(size 1.27 1.27)
				)
				(justify mirror)
			)
		)
		(duplicate_pad_numbers_are_jumpers no)
		(pad "" np_thru_hole circle
			(at -1.35001 -2.54)
			(size 2.5146 2.5146)
			(drill 2.5146)
			(layers "*.Cu" "*.Mask")
			(clearance 0.381)
			(thermal_gap 0.381)
		)
		(pad "" np_thru_hole circle
			(at 0 50.8)
			(size 2.5146 2.5146)
			(drill 2.5146)
			(layers "*.Cu" "*.Mask")
			(clearance 0.381)
			(thermal_gap 0.381)
		)
		(pad "P1" thru_hole rect
			(at 0 0)
			(size 1.1684 1.1684)
			(drill 0.762)
			(layers "*.Cu" "*.Mask")
			(remove_unused_layers no)
			(net "GND")
			(clearance 0.0508)
			(padstack
				(mode front_inner_back)
				(layer "Inner"
					(shape circle)
					(size 1.1684 1.1684)
					(clearance 0.0508)
				)
				(layer "B.Cu"
					(shape rect)
					(size 1.1684 1.1684)
					(thermal_gap 0.0508)
					(clearance 0.0508)
				)
			)
		)
		(pad "P2" thru_hole circle
			(at 0 2.54)
			(size 1.1684 1.1684)
			(drill 0.762)
			(layers "*.Cu" "*.Mask")
			(remove_unused_layers no)
			(net "GND")
			(clearance 0.0508)
			(thermal_gap 0.0508)
		)
		(pad "P3" thru_hole circle
			(at 0 5.08)
			(size 1.1684 1.1684)
			(drill 0.762)
			(layers "*.Cu" "*.Mask")
			(remove_unused_layers no)
			(net "GND")
			(clearance 0.0508)
			(thermal_gap 0.0508)
		)
		(pad "P4" thru_hole circle
			(at 0 7.62)
			(size 1.1684 1.1684)
			(drill 0.762)
			(layers "*.Cu" "*.Mask")
			(remove_unused_layers no)
			(net "GND")
			(clearance 0.0508)
			(thermal_gap 0.0508)
		)
		(pad "P5" thru_hole circle
			(at 0 10.16)
			(size 1.1684 1.1684)
			(drill 0.762)
			(layers "*.Cu" "*.Mask")
			(remove_unused_layers no)
			(net "GND")
			(clearance 0.0508)
			(thermal_gap 0.0508)
		)
		(pad "P6" thru_hole circle
			(at 0 12.7)
			(size 1.1684 1.1684)
			(drill 0.762)
			(layers "*.Cu" "*.Mask")
			(remove_unused_layers no)
			(net "GND")
			(clearance 0.0508)
			(thermal_gap 0.0508)
		)
		(pad "P7" thru_hole circle
			(at 0 15.24)
			(size 1.1684 1.1684)
			(drill 0.762)
			(layers "*.Cu" "*.Mask")
			(remove_unused_layers no)
			(net "GND")
			(clearance 0.0508)
			(thermal_gap 0.0508)
		)
		(pad "P8" thru_hole circle
			(at 0 17.78)
			(size 1.1684 1.1684)
			(drill 0.762)
			(layers "*.Cu" "*.Mask")
			(remove_unused_layers no)
			(net "GND")
			(clearance 0.0508)
			(thermal_gap 0.0508)
		)
		(pad "P9" thru_hole circle
			(at 0 20.32)
			(size 1.1684 1.1684)
			(drill 0.762)
			(layers "*.Cu" "*.Mask")
			(remove_unused_layers no)
			(net "P12V")
			(clearance 0.0508)
			(thermal_gap 0.0508)
		)
		(pad "P10" thru_hole circle
			(at 0 22.86)
			(size 1.1684 1.1684)
			(drill 0.762)
			(layers "*.Cu" "*.Mask")
			(remove_unused_layers no)
			(net "P12V")
			(clearance 0.0508)
			(thermal_gap 0.0508)
		)
		(pad "P11" thru_hole circle
			(at 0 25.4)
			(size 1.1684 1.1684)
			(drill 0.762)
			(layers "*.Cu" "*.Mask")
			(remove_unused_layers no)
			(net "P12V")
			(clearance 0.0508)
			(thermal_gap 0.0508)
		)
		(pad "P12" thru_hole circle
			(at 0 27.94)
			(size 1.1684 1.1684)
			(drill 0.762)
			(layers "*.Cu" "*.Mask")
			(remove_unused_layers no)
			(net "P12V")
			(clearance 0.0508)
			(thermal_gap 0.0508)
		)
		(pad "P13" thru_hole circle
			(at 0 30.48)
			(size 1.1684 1.1684)
			(drill 0.762)
			(layers "*.Cu" "*.Mask")
			(remove_unused_layers no)
			(net "P12V")
			(clearance 0.0508)
			(thermal_gap 0.0508)
		)
		(pad "P14" thru_hole circle
			(at 0 33.02)
			(size 1.1684 1.1684)
			(drill 0.762)
			(layers "*.Cu" "*.Mask")
			(remove_unused_layers no)
			(net "P12V")
			(clearance 0.0508)
			(thermal_gap 0.0508)
		)
		(pad "P15" thru_hole circle
			(at 0 35.56)
			(size 1.1684 1.1684)
			(drill 0.762)
			(layers "*.Cu" "*.Mask")
			(remove_unused_layers no)
			(net "P12V")
			(clearance 0.0508)
			(thermal_gap 0.0508)
		)
		(pad "P16" thru_hole circle
			(at 0 38.1)
			(size 1.1684 1.1684)
			(drill 0.762)
			(layers "*.Cu" "*.Mask")
			(remove_unused_layers no)
			(net "P12V")
			(clearance 0.0508)
			(thermal_gap 0.0508)
		)
		(pad "P17" thru_hole circle
			(at -2.70002 38.1)
			(size 1.1684 1.1684)
			(drill 0.762)
			(layers "*.Cu" "*.Mask")
			(remove_unused_layers no)
			(net "P12V")
			(clearance 0.0508)
			(thermal_gap 0.0508)
		)
		(pad "P18" thru_hole circle
			(at -2.70002 35.56)
			(size 1.1684 1.1684)
			(drill 0.762)
			(layers "*.Cu" "*.Mask")
			(remove_unused_layers no)
			(net "P12V")
			(clearance 0.0508)
			(thermal_gap 0.0508)
		)
		(pad "P19" thru_hole circle
			(at -2.70002 33.02)
			(size 1.1684 1.1684)
			(drill 0.762)
			(layers "*.Cu" "*.Mask")
			(remove_unused_layers no)
			(net "P12V")
			(clearance 0.0508)
			(thermal_gap 0.0508)
		)
		(pad "P20" thru_hole circle
			(at -2.70002 30.48)
			(size 1.1684 1.1684)
			(drill 0.762)
			(layers "*.Cu" "*.Mask")
			(remove_unused_layers no)
			(net "P12V")
			(clearance 0.0508)
			(thermal_gap 0.0508)
		)
		(pad "P21" thru_hole circle
			(at -2.70002 27.94)
			(size 1.1684 1.1684)
			(drill 0.762)
			(layers "*.Cu" "*.Mask")
			(remove_unused_layers no)
			(net "P12V")
			(clearance 0.0508)
			(thermal_gap 0.0508)
		)
		(pad "P22" thru_hole circle
			(at -2.70002 25.4)
			(size 1.1684 1.1684)
			(drill 0.762)
			(layers "*.Cu" "*.Mask")
			(remove_unused_layers no)
			(net "P12V")
			(clearance 0.0508)
			(thermal_gap 0.0508)
		)
		(pad "P23" thru_hole circle
			(at -2.70002 22.86)
			(size 1.1684 1.1684)
			(drill 0.762)
			(layers "*.Cu" "*.Mask")
			(remove_unused_layers no)
			(net "P12V")
			(clearance 0.0508)
			(thermal_gap 0.0508)
		)
		(pad "P24" thru_hole circle
			(at -2.70002 20.32)
			(size 1.1684 1.1684)
			(drill 0.762)
			(layers "*.Cu" "*.Mask")
			(remove_unused_layers no)
			(net "P12V")
			(clearance 0.0508)
			(thermal_gap 0.0508)
		)
		(pad "P25" thru_hole circle
			(at -2.70002 17.78)
			(size 1.1684 1.1684)
			(drill 0.762)
			(layers "*.Cu" "*.Mask")
			(remove_unused_layers no)
			(net "GND")
			(clearance 0.0508)
			(thermal_gap 0.0508)
		)
		(pad "P26" thru_hole circle
			(at -2.70002 15.24)
			(size 1.1684 1.1684)
			(drill 0.762)
			(layers "*.Cu" "*.Mask")
			(remove_unused_layers no)
			(net "GND")
			(clearance 0.0508)
			(thermal_gap 0.0508)
		)
		(pad "P27" thru_hole circle
			(at -2.70002 12.7)
			(size 1.1684 1.1684)
			(drill 0.762)
			(layers "*.Cu" "*.Mask")
			(remove_unused_layers no)
			(net "GND")
			(clearance 0.0508)
			(thermal_gap 0.0508)
		)
		(pad "P28" thru_hole circle
			(at -2.70002 10.16)
			(size 1.1684 1.1684)
			(drill 0.762)
			(layers "*.Cu" "*.Mask")
			(remove_unused_layers no)
			(net "GND")
			(clearance 0.0508)
			(thermal_gap 0.0508)
		)
		(pad "P29" thru_hole circle
			(at -2.70002 7.62)
			(size 1.1684 1.1684)
			(drill 0.762)
			(layers "*.Cu" "*.Mask")
			(remove_unused_layers no)
			(net "GND")
			(clearance 0.0508)
			(thermal_gap 0.0508)
		)
		(pad "P30" thru_hole circle
			(at -2.70002 5.08)
			(size 1.1684 1.1684)
			(drill 0.762)
			(layers "*.Cu" "*.Mask")
			(remove_unused_layers no)
			(net "GND")
			(clearance 0.0508)
			(thermal_gap 0.0508)
		)
		(pad "P31" thru_hole circle
			(at -2.70002 2.54)
			(size 1.1684 1.1684)
			(drill 0.762)
			(layers "*.Cu" "*.Mask")
			(remove_unused_layers no)
			(net "GND")
			(clearance 0.0508)
			(thermal_gap 0.0508)
		)
		(pad "P32" thru_hole circle
			(at -2.70002 0)
			(size 1.1684 1.1684)
			(drill 0.762)
			(layers "*.Cu" "*.Mask")
			(remove_unused_layers no)
			(net "GND")
			(clearance 0.0508)
			(thermal_gap 0.0508)
		)
		(pad "S1" thru_hole circle
			(at 0.55499 41.60012)
			(size 1.1684 1.1684)
			(drill 0.762)
			(layers "*.Cu" "*.Mask")
			(remove_unused_layers no)
			(net "T4_BLAD1_TXD")
			(clearance 0.0508)
			(thermal_gap 0.0508)
		)
		(pad "S2" thru_hole circle
			(at -0.71501 42.87012)
			(size 1.1684 1.1684)
			(drill 0.762)
			(layers "*.Cu" "*.Mask")
			(remove_unused_layers no)
			(net "T4_BLAD1_RXD")
			(clearance 0.0508)
			(thermal_gap 0.0508)
		)
		(pad "S3" thru_hole circle
			(at 0.55499 44.14012)
			(size 1.1684 1.1684)
			(drill 0.762)
			(layers "*.Cu" "*.Mask")
			(remove_unused_layers no)
			(net "T4_BLAD1_EN")
			(clearance 0.0508)
			(thermal_gap 0.0508)
		)
		(pad "S4" thru_hole circle
			(at -0.71501 45.41012)
			(size 1.1684 1.1684)
			(drill 0.762)
			(layers "*.Cu" "*.Mask")
			(remove_unused_layers no)
			(net "T4_BLAD2_EN")
			(clearance 0.0508)
			(thermal_gap 0.0508)
		)
		(pad "S5" thru_hole circle
			(at 0.55499 46.68012)
			(size 1.1684 1.1684)
			(drill 0.762)
			(layers "*.Cu" "*.Mask")
			(remove_unused_layers no)
			(net "T4_BLAD2_TXD")
			(clearance 0.0508)
			(thermal_gap 0.0508)
		)
		(pad "S6" thru_hole circle
			(at -0.71501 47.95012)
			(size 1.1684 1.1684)
			(drill 0.762)
			(layers "*.Cu" "*.Mask")
			(remove_unused_layers no)
			(net "T4_BLAD2_RXD")
			(clearance 0.0508)
			(thermal_gap 0.0508)
		)
		(pad "S7" thru_hole circle
			(at -3.25501 47.95012)
			(size 1.1684 1.1684)
			(drill 0.762)
			(layers "*.Cu" "*.Mask")
			(remove_unused_layers no)
			(net "T4_BLAD4_RXD")
			(clearance 0.0508)
			(thermal_gap 0.0508)
		)
		(pad "S8" thru_hole circle
			(at -1.98501 46.68012)
			(size 1.1684 1.1684)
			(drill 0.762)
			(layers "*.Cu" "*.Mask")
			(remove_unused_layers no)
			(net "T4_BLAD4_TXD")
			(clearance 0.0508)
			(thermal_gap 0.0508)
		)
		(pad "S9" thru_hole circle
			(at -3.25501 45.41012)
			(size 1.1684 1.1684)
			(drill 0.762)
			(layers "*.Cu" "*.Mask")
			(remove_unused_layers no)
			(net "T4_BLAD4_EN")
			(clearance 0.0508)
			(thermal_gap 0.0508)
		)
		(pad "S10" thru_hole circle
			(at -1.98501 44.14012)
			(size 1.1684 1.1684)
			(drill 0.762)
			(layers "*.Cu" "*.Mask")
			(remove_unused_layers no)
			(net "T4_BLAD3_EN")
			(clearance 0.0508)
			(thermal_gap 0.0508)
		)
		(pad "S11" thru_hole circle
			(at -3.25501 42.87012)
			(size 1.1684 1.1684)
			(drill 0.762)
			(layers "*.Cu" "*.Mask")
			(remove_unused_layers no)
			(net "T4_BLAD3_RXD")
			(clearance 0.0508)
			(thermal_gap 0.0508)
		)
		(pad "S12" thru_hole circle
			(at -1.98501 41.60012)
			(size 1.1684 1.1684)
			(drill 0.762)
			(layers "*.Cu" "*.Mask")
			(remove_unused_layers no)
			(net "T4_BLAD3_TXD")
			(clearance 0.0508)
			(thermal_gap 0.0508)
		)
	)
)
